# S9S_MB_2U (Grand Teton) — schematic netlist excerpt (pin names and nets, part order shuffled) for the footprints in the layout excerpt that follows; sources: Cadence DE-HDL packaged netlist, KiCad conversion of 03242023_DA0F0TMBIJ0_F0T_Motherboard_J_brd_V01_OCP.brd

J3  SCONN288_ADR50017P130CC  SCONN288_ADR50017-P130CC IO  pkg DDR288S_1-1VXB  page 84
  VIN_BULK0  = P12V_S3_AUX_CPU0_NVDIMM
  RFU0  = TP_CHB_CPU0_DIMM1_FRU_0
  VIN_MGMT  = P3V3_AUX
  HSCL  = I3C_SPD_DDRABCD_CPU0_LVC1_SCL_2
  HSDA  = I3C_SPD_DDRABCD_CPU0_LVC1_SDA
  VSS0  = GND
  DQ0_A  = M_B_CPU0_SA_DQ<0>
  VSS1  = GND
  DQ1_A  = M_B_CPU0_SA_DQ<1>
  VSS2  = GND
  DQS0_A_T  = M_B_CPU0_SA_DQS_DP<0>
  DQS0_A_C  = M_B_CPU0_SA_DQS_DN<0>
  VSS3  = GND
  DQ4_A  = M_B_CPU0_SA_DQ<4>
  VSS4  = GND
  DQ5_A  = M_B_CPU0_SA_DQ<5>
  VSS5  = GND
  DQ8_A  = M_B_CPU0_SA_DQ<8>
  VSS6  = GND
  DQ9_A  = M_B_CPU0_SA_DQ<9>
  VSS7  = GND
  DQS1_A_T  = M_B_CPU0_SA_DQS_DP<1>
  DQS1_A_C  = M_B_CPU0_SA_DQS_DN<1>
  VSS8  = GND
  DQ12_A  = M_B_CPU0_SA_DQ<12>
  VSS9  = GND
  DQ13_A  = M_B_CPU0_SA_DQ<13>
  VSS10  = GND
  DQ16_A  = M_B_CPU0_SA_DQ<16>
  VSS11  = GND
  DQ17_A  = M_B_CPU0_SA_DQ<17>
  VSS12  = GND
  DQS2_A_T  = M_B_CPU0_SA_DQS_DP<2>
  DQS2_A_C  = M_B_CPU0_SA_DQS_DN<2>
  VSS13  = GND
  DQ20_A  = M_B_CPU0_SA_DQ<20>
  VSS14  = GND
  DQ21_A  = M_B_CPU0_SA_DQ<21>
  VSS15  = GND
  DQ24_A  = M_B_CPU0_SA_DQ<24>
  VSS16  = GND
  DQ25_A  = M_B_CPU0_SA_DQ<25>
  VSS17  = GND
  DQS3_A_T  = M_B_CPU0_SA_DQS_DP<3>
  DQS3_A_C  = M_B_CPU0_SA_DQS_DN<3>
  VSS18  = GND
  DQ28_A  = M_B_CPU0_SA_DQ<28>
  VSS19  = GND
  DQ29_A  = M_B_CPU0_SA_DQ<29>
  VSS20  = GND
  CB0_A  = M_B_CPU0_SA_CB<0>
  VSS21  = GND
  CB1_A  = M_B_CPU0_SA_CB<1>
  VSS22  = GND
  DQS4_A_T  = M_B_CPU0_SA_DQS_DP<4>
  DQS4_A_C  = M_B_CPU0_SA_DQS_DN<4>
  VSS23  = GND
  CB4_A  = M_B_CPU0_SA_CB<4>
  VSS24  = GND
  CB5_A  = M_B_CPU0_SA_CB<5>
  VSS25  = GND
  ALERT_N  = M_B_CPU0_ALERT_N
  VSS26  = GND
  CS0_A_N  = M_B_CPU0_SA_CS_N<0>
  VSS27  = GND
  CA0_A  = M_B_CPU0_SA_CA<0>
  VSS28  = GND
  CA2_A  = M_B_CPU0_SA_CA<2>
  VSS29  = GND
  CA4_A  = M_B_CPU0_SA_CA<4>
  VSS30  = GND
  CA6_A  = M_B_CPU0_SA_CA<6>
  VSS31  = GND
  PAR_A  = M_B_CPU0_SA_PAR
  VSS32  = GND
  CA0_B  = M_B_CPU0_SB_CA<0>
  VSS33  = GND
  CA2_B  = M_B_CPU0_SB_CA<2>
  VSS34  = GND
  CA4_B  = M_B_CPU0_SB_CA<4>
  VSS35  = GND
  CA6_B  = M_B_CPU0_SB_CA<6>
  VSS36  = GND
  CS0_B_N  = M_B_CPU0_SB_CS_N<0>
  VSS37  = GND
  \lbd||rsp_a_n\  = M_B_CPU0_SA_RSP<0>
  \lbs||rsp_b_n\  = M_B_CPU0_SB_RSP<0>
  VSS38  = GND
  CB4_B  = M_B_CPU0_SB_CB<4>
  VSS39  = GND
  CB5_B  = M_B_CPU0_SB_CB<5>
  VSS40  = GND
  \dqs9_b_t||tdqs9_b_t||dbi4_b_n\  = M_B_CPU0_SB_DQS_DP<9>
  \dqs9_b_c||tdqs9_b_c\  = M_B_CPU0_SB_DQS_DN<9>
  VSS41  = GND
  CB0_B  = M_B_CPU0_SB_CB<0>
  VSS42  = GND
  CB1_B  = M_B_CPU0_SB_CB<1>
  VSS43  = GND
  DQ0_B  = M_B_CPU0_SB_DQ<0>
  VSS44  = GND
  DQ1_B  = M_B_CPU0_SB_DQ<1>
  VSS45  = GND
  DQS0_B_T  = M_B_CPU0_SB_DQS_DP<0>
  DQS0_B_C  = M_B_CPU0_SB_DQS_DN<0>
  VSS46  = GND
  DQ4_B  = M_B_CPU0_SB_DQ<4>
  VSS47  = GND
  DQ5_B  = M_B_CPU0_SB_DQ<5>
  VSS48  = GND
  DQ8_B  = M_B_CPU0_SB_DQ<8>
  VSS49  = GND
  DQ9_B  = M_B_CPU0_SB_DQ<9>
  VSS50  = GND
  DQS1_B_T  = M_B_CPU0_SB_DQS_DP<1>
  DQS1_B_C  = M_B_CPU0_SB_DQS_DN<1>
  VSS51  = GND
  DQ12_B  = M_B_CPU0_SB_DQ<12>
  VSS52  = GND
  DQ13_B  = M_B_CPU0_SB_DQ<13>
  VSS53  = GND
  DQ16_B  = M_B_CPU0_SB_DQ<16>
  VSS54  = GND
  DQ17_B  = M_B_CPU0_SB_DQ<17>
  VSS55  = GND
  DQS2_B_T  = M_B_CPU0_SB_DQS_DP<2>
  DQS2_B_C  = M_B_CPU0_SB_DQS_DN<2>
  VSS56  = GND
  DQ20_B  = M_B_CPU0_SB_DQ<20>
  VSS57  = GND
  DQ21_B  = M_B_CPU0_SB_DQ<21>
  VSS58  = GND
  DQ24_B  = M_B_CPU0_SB_DQ<24>
  VSS59  = GND
  DQ25_B  = M_B_CPU0_SB_DQ<25>
  VSS60  = GND
  DQS3_B_T  = M_B_CPU0_SB_DQS_DP<3>
  DQS3_B_C  = M_B_CPU0_SB_DQS_DN<3>
  VSS61  = GND
  DQ28_B  = M_B_CPU0_SB_DQ<28>
  VSS62  = GND
  DQ29_B  = M_B_CPU0_SB_DQ<29>
  VSS63  = GND
  RFU1  = TP_CHB_CPU0_DIMM1_FRU_1
  VIN_BULK1  = P12V_S3_AUX_CPU0_NVDIMM
  VIN_BULK2  = P12V_S3_AUX_CPU0_NVDIMM
  \pwr_good||fail_n\  = PWRGD_CHB_CPU0_DIMM1
  HSA  = PD_CHB_CPU0_DIMM1_SAA
  RFU2  = TP_CHB_CPU0_DIMM1_FRU_2
  RFU3  = TP_CHB_CPU0_DIMM1_FRU_3
  VSS64  = GND
  DQ2_A  = M_B_CPU0_SA_DQ<2>
  VSS65  = GND
  DQ3_A  = M_B_CPU0_SA_DQ<3>
  VSS66  = GND
  \dqs5_a_c||tdqs5_a_c||dqs5_a_t||tdqs5_a_t\  = M_B_CPU0_SA_DQS_DN<5>
  \dqs5_a_t||tdqs5_a_t\  = M_B_CPU0_SA_DQS_DP<5>
  VSS67  = GND
  DQ6_A  = M_B_CPU0_SA_DQ<6>
  VSS68  = GND
  DQ7_A  = M_B_CPU0_SA_DQ<7>
  VSS69  = GND
  DQ10_A  = M_B_CPU0_SA_DQ<10>
  VSS70  = GND
  DQ11_A  = M_B_CPU0_SA_DQ<11>
  VSS71  = GND
  \dqs6_a_c||tdqs6_a_c||dqs6_a_t||tdqs6_a_t\  = M_B_CPU0_SA_DQS_DN<6>
  \dqs6_a_t||tdqs6_a_t\  = M_B_CPU0_SA_DQS_DP<6>
  VSS72  = GND
  DQ14_A  = M_B_CPU0_SA_DQ<14>
  VSS73  = GND
  DQ15_A  = M_B_CPU0_SA_DQ<15>
  VSS74  = GND
  DQ18_A  = M_B_CPU0_SA_DQ<18>
  VSS75  = GND
  DQ19_A  = M_B_CPU0_SA_DQ<19>
  VSS76  = GND
  \dqs7_a_c||tdqs7_a_c\  = M_B_CPU0_SA_DQS_DN<7>
  \dqs7_a_t||tdqs7_a_t\  = M_B_CPU0_SA_DQS_DP<7>
  VSS77  = GND
  DQ22_A  = M_B_CPU0_SA_DQ<22>
  VSS78  = GND
  DQ23_A  = M_B_CPU0_SA_DQ<23>
  VSS79  = GND
  DQ26_A  = M_B_CPU0_SA_DQ<26>
  VSS80  = GND
  DQ27_A  = M_B_CPU0_SA_DQ<27>
  VSS81  = GND
  \dqs8_a_c||tdqs8_a_c\  = M_B_CPU0_SA_DQS_DN<8>
  \dqs8_a_t||tdqs8_a_t\  = M_B_CPU0_SA_DQS_DP<8>
  VSS82  = GND
  DQ30_A  = M_B_CPU0_SA_DQ<30>
  VSS83  = GND
  DQ31_A  = M_B_CPU0_SA_DQ<31>
  VSS84  = GND
  CB2_A  = M_B_CPU0_SA_CB<2>
  VSS85  = GND
  CB3_A  = M_B_CPU0_SA_CB<3>
  VSS86  = GND
  \dqs9_a_c||tdqs9_a_c\  = M_B_CPU0_SA_DQS_DN<9>
  \dqs9_a_t||tdqs9_a_t\  = M_B_CPU0_SA_DQS_DP<9>
  VSS87  = GND
  CB6_A  = M_B_CPU0_SA_CB<6>
  VSS88  = GND
  CB7_A  = M_B_CPU0_SA_CB<7>
  VSS89  = GND
  RESET_N  = RST_M_AB_CPU0_FPGA_N
  VSS90  = GND
  CS1_A_N  = M_B_CPU0_SA_CS_N<1>
  VSS91  = GND
  CA1_A  = M_B_CPU0_SA_CA<1>
  VSS92  = GND
  CA3_A  = M_B_CPU0_SA_CA<3>
  VSS93  = GND
  CA5_A  = M_B_CPU0_SA_CA<5>
  VSS94  = GND
  CK_T  = M_B_CPU0_CLK_DP<0>
  CK_C  = M_B_CPU0_CLK_DN<0>
  VSS95  = GND
  RFU4  = TP_CHB_CPU0_DIMM1_FRU_4
  CA1_B  = M_B_CPU0_SB_CA<1>
  VSS96  = GND
  CA3_B  = M_B_CPU0_SB_CA<3>
  VSS97  = GND
  CA5_B  = M_B_CPU0_SB_CA<5>
  VSS98  = GND
  PAR_B  = M_B_CPU0_SB_PAR
  VSS99  = GND
  CS1_B_N  = M_B_CPU0_SB_CS_N<1>
  VSS100  = GND
  RFU5  = TP_CHB_CPU0_DIMM1_FRU_5
  RFU6  = TP_CHB_CPU0_DIMM1_FRU_6
  VSS101  = GND
  CB6_B  = M_B_CPU0_SB_CB<6>
  VSS102  = GND
  CB7_B  = M_B_CPU0_SB_CB<7>
  VSS103  = GND
  DQS4_B_C  = M_B_CPU0_SB_DQS_DN<4>
  DQS4_B_T  = M_B_CPU0_SB_DQS_DP<4>
  VSS104  = GND
  CB2_B  = M_B_CPU0_SB_CB<2>
  VSS105  = GND
  CB3_B  = M_B_CPU0_SB_CB<3>
  VSS106  = GND
  DQ2_B  = M_B_CPU0_SB_DQ<2>
  VSS107  = GND
  DQ3_B  = M_B_CPU0_SB_DQ<3>
  VSS108  = GND
  \dqs5_b_c||tdqs5_b_c\  = M_B_CPU0_SB_DQS_DN<5>
  \dqs5_b_t||tdqs5_b_t\  = M_B_CPU0_SB_DQS_DP<5>
  VSS109  = GND
  DQ6_B  = M_B_CPU0_SB_DQ<6>
  VSS110  = GND
  DQ7_B  = M_B_CPU0_SB_DQ<7>
  VSS111  = GND
  DQ10_B  = M_B_CPU0_SB_DQ<10>
  VSS112  = GND
  DQ11_B  = M_B_CPU0_SB_DQ<11>
  VSS113  = GND
  \dqs6_b_c||tdqs6_b_c\  = M_B_CPU0_SB_DQS_DN<6>
  \dqs6_b_t||tdqs6_b_t\  = M_B_CPU0_SB_DQS_DP<6>
  VSS114  = GND
  DQ14_B  = M_B_CPU0_SB_DQ<14>
  VSS115  = GND
  DQ15_B  = M_B_CPU0_SB_DQ<15>
  VSS116  = GND
  DQ18_B  = M_B_CPU0_SB_DQ<18>
  VSS117  = GND
  DQ19_B  = M_B_CPU0_SB_DQ<19>
  VSS118  = GND
  \dqs7_b_c||tdqs7_b_c\  = M_B_CPU0_SB_DQS_DN<7>
  \dqs7_b_t||tdqs7_b_t\  = M_B_CPU0_SB_DQS_DP<7>
  VSS119  = GND
  DQ22_B  = M_B_CPU0_SB_DQ<22>
  VSS120  = GND
  DQ23_B  = M_B_CPU0_SB_DQ<23>
  VSS121  = GND
  DQ26_B  = M_B_CPU0_SB_DQ<26>
  VSS122  = GND
  DQ27_B  = M_B_CPU0_SB_DQ<27>
  VSS123  = GND
  \dqs8_b_c||tdqs8_b_c\  = M_B_CPU0_SB_DQS_DN<8>
  \dqs8_b_t||tdqs8_b_t\  = M_B_CPU0_SB_DQS_DP<8>
  VSS124  = GND
  DQ30_B  = M_B_CPU0_SB_DQ<30>
  VSS125  = GND
  DQ31_B  = M_B_CPU0_SB_DQ<31>
  VSS126  = GND
  G1  = GND
  G2  = GND
  G3  = GND

(kicad_pcb
	(version 20260206)
	(generator "pcbnew")
	(generator_version "10.0")
	(general
		(thickness 1.6)
		(legacy_teardrops no)
	)
	(paper "A4")
	(title_block
		(title "03242023_DA0F0TMBIJ0_F0T_Motherboard_J_brd_V01_OCP.brd")
		(comment 1 "Grand Teton / footprint 2048 of 6105 (J3), pads 1-45 of 291")
	)
	(layers
		(0 "F.Cu" signal "TOP")
		(4 "In1.Cu" signal "GND")
		(6 "In2.Cu" signal "IN1")
		(8 "In3.Cu" signal "GND1")
		(10 "In4.Cu" signal "IN2")
		(12 "In5.Cu" signal "GND2")
		(14 "In6.Cu" signal "IN3")
		(16 "In7.Cu" signal "GND3")
		(18 "In8.Cu" signal "VCC")
		(20 "In9.Cu" signal "VCC1")
		(22 "In10.Cu" signal "GND4")
		(24 "In11.Cu" signal "IN4")
		(26 "In12.Cu" signal "GND5")
		(28 "In13.Cu" signal "IN5")
		(30 "In14.Cu" signal "GND6")
		(32 "In15.Cu" signal "IN6")
		(34 "In16.Cu" signal "GND7")
		(2 "B.Cu" signal "BOTTOM")
		(9 "F.Adhes" user "F.Adhesive")
		(11 "B.Adhes" user "B.Adhesive")
		(13 "F.Paste" user "Package Geometry/Pastemask Top")
		(15 "B.Paste" user "Package Geometry/Pastemask Bottom")
		(5 "F.SilkS" user "Ref Des/Silkscreen Top")
		(7 "B.SilkS" user "Ref Des/Silkscreen Bottom")
		(1 "F.Mask" user "Board Geometry/Soldermask Top")
		(3 "B.Mask" user "Board Geometry/Soldermask Bottom")
		(17 "Dwgs.User" user "User.Drawings")
		(19 "Cmts.User" user "User.Comments")
		(21 "Eco1.User" user "User.Eco1")
		(23 "Eco2.User" user "User.Eco2")
		(25 "Edge.Cuts" user "Board Geometry/Outline")
		(27 "Margin" user)
		(31 "F.CrtYd" user "Package Geometry/Place Bound Top")
		(29 "B.CrtYd" user "Package Geometry/Place Bound Bottom")
		(35 "F.Fab" user "Ref Des/Assembly Top")
		(33 "B.Fab" user "Ref Des/Assembly Bottom")
	)
	(footprint ""
		(layer "F.Cu")
		(at 288.305748 -258.091686)
		(property "Reference" "J3"
			(at -3.683 -81.702148 0)
			(unlocked yes)
			(layer "F.SilkS")
			(effects
				(font
					(size 0.7874 0.5842)
					(thickness 0.1524)
				)
				(justify left)
			)
		)
		(property "Value" ""
			(at 0 0 0)
			(layer "F.Fab")
			(effects
				(font
					(size 1.27 1.27)
				)
			)
		)
		(duplicate_pad_numbers_are_jumpers no)
		(pad "1" smd rect
			(at -2.050034 -63.324994 270)
			(size 0.519938 1.4986)
			(layers "F.Cu" "F.Mask" "F.Paste")
			(net "P12V_S3_AUX_CPU0_NVDIMM")
		)
		(pad "2" smd rect
			(at -2.050034 -62.47511 270)
			(size 0.519938 1.4986)
			(layers "F.Cu" "F.Mask" "F.Paste")
			(net "TP_CHB_CPU0_DIMM1_FRU_0")
		)
		(pad "3" smd rect
			(at -2.050034 -61.624972 270)
			(size 0.519938 1.4986)
			(layers "F.Cu" "F.Mask" "F.Paste")
			(net "P3V3_AUX")
		)
		(pad "4" smd rect
			(at -2.050034 -60.775088 270)
			(size 0.519938 1.4986)
			(layers "F.Cu" "F.Mask" "F.Paste")
			(net "I3C_SPD_DDRABCD_CPU0_LVC1_SCL_2")
		)
		(pad "5" smd rect
			(at -2.050034 -59.92495 270)
			(size 0.519938 1.4986)
			(layers "F.Cu" "F.Mask" "F.Paste")
			(net "I3C_SPD_DDRABCD_CPU0_LVC1_SDA")
		)
		(pad "6" smd rect
			(at -2.050034 -59.075066 270)
			(size 0.519938 1.4986)
			(layers "F.Cu" "F.Mask" "F.Paste")
			(net "GND")
		)
		(pad "7" smd rect
			(at -2.050034 -58.224928 270)
			(size 0.519938 1.4986)
			(layers "F.Cu" "F.Mask" "F.Paste")
			(net "M_B_CPU0_SA_DQ<0>")
		)
		(pad "8" smd rect
			(at -2.050034 -57.375044 270)
			(size 0.519938 1.4986)
			(layers "F.Cu" "F.Mask" "F.Paste")
			(net "GND")
		)
		(pad "9" smd rect
			(at -2.050034 -56.524906 270)
			(size 0.519938 1.4986)
			(layers "F.Cu" "F.Mask" "F.Paste")
			(net "M_B_CPU0_SA_DQ<1>")
		)
		(pad "10" smd rect
			(at -2.050034 -55.675022 270)
			(size 0.519938 1.4986)
			(layers "F.Cu" "F.Mask" "F.Paste")
			(net "GND")
		)
		(pad "11" smd rect
			(at -2.050034 -54.824884 270)
			(size 0.519938 1.4986)
			(layers "F.Cu" "F.Mask" "F.Paste")
			(net "M_B_CPU0_SA_DQS_DP<0>")
		)
		(pad "12" smd rect
			(at -2.050034 -53.975 270)
			(size 0.519938 1.4986)
			(layers "F.Cu" "F.Mask" "F.Paste")
			(net "M_B_CPU0_SA_DQS_DN<0>")
		)
		(pad "13" smd rect
			(at -2.050034 -53.125116 270)
			(size 0.519938 1.4986)
			(layers "F.Cu" "F.Mask" "F.Paste")
			(net "GND")
		)
		(pad "14" smd rect
			(at -2.050034 -52.274978 270)
			(size 0.519938 1.4986)
			(layers "F.Cu" "F.Mask" "F.Paste")
			(net "M_B_CPU0_SA_DQ<4>")
		)
		(pad "15" smd rect
			(at -2.050034 -51.425094 270)
			(size 0.519938 1.4986)
			(layers "F.Cu" "F.Mask" "F.Paste")
			(net "GND")
		)
		(pad "16" smd rect
			(at -2.050034 -50.574956 270)
			(size 0.519938 1.4986)
			(layers "F.Cu" "F.Mask" "F.Paste")
			(net "M_B_CPU0_SA_DQ<5>")
		)
		(pad "17" smd rect
			(at -2.050034 -49.725072 270)
			(size 0.519938 1.4986)
			(layers "F.Cu" "F.Mask" "F.Paste")
			(net "GND")
		)
		(pad "18" smd rect
			(at -2.050034 -48.874934 270)
			(size 0.519938 1.4986)
			(layers "F.Cu" "F.Mask" "F.Paste")
			(net "M_B_CPU0_SA_DQ<8>")
		)
		(pad "19" smd rect
			(at -2.050034 -48.02505 270)
			(size 0.519938 1.4986)
			(layers "F.Cu" "F.Mask" "F.Paste")
			(net "GND")
		)
		(pad "20" smd rect
			(at -2.050034 -47.174912 270)
			(size 0.519938 1.4986)
			(layers "F.Cu" "F.Mask" "F.Paste")
			(net "M_B_CPU0_SA_DQ<9>")
		)
		(pad "21" smd rect
			(at -2.050034 -46.325028 270)
			(size 0.519938 1.4986)
			(layers "F.Cu" "F.Mask" "F.Paste")
			(net "GND")
		)
		(pad "22" smd rect
			(at -2.050034 -45.47489 270)
			(size 0.519938 1.4986)
			(layers "F.Cu" "F.Mask" "F.Paste")
			(net "M_B_CPU0_SA_DQS_DP<1>")
		)
		(pad "23" smd rect
			(at -2.050034 -44.625006 270)
			(size 0.519938 1.4986)
			(layers "F.Cu" "F.Mask" "F.Paste")
			(net "M_B_CPU0_SA_DQS_DN<1>")
		)
		(pad "24" smd rect
			(at -2.050034 -43.775122 270)
			(size 0.519938 1.4986)
			(layers "F.Cu" "F.Mask" "F.Paste")
			(net "GND")
		)
		(pad "25" smd rect
			(at -2.050034 -42.924984 270)
			(size 0.519938 1.4986)
			(layers "F.Cu" "F.Mask" "F.Paste")
			(net "M_B_CPU0_SA_DQ<12>")
		)
		(pad "26" smd rect
			(at -2.050034 -42.0751 270)
			(size 0.519938 1.4986)
			(layers "F.Cu" "F.Mask" "F.Paste")
			(net "GND")
		)
		(pad "27" smd rect
			(at -2.050034 -41.224962 270)
			(size 0.519938 1.4986)
			(layers "F.Cu" "F.Mask" "F.Paste")
			(net "M_B_CPU0_SA_DQ<13>")
		)
		(pad "28" smd rect
			(at -2.050034 -40.375078 270)
			(size 0.519938 1.4986)
			(layers "F.Cu" "F.Mask" "F.Paste")
			(net "GND")
		)
		(pad "29" smd rect
			(at -2.050034 -39.52494 270)
			(size 0.519938 1.4986)
			(layers "F.Cu" "F.Mask" "F.Paste")
			(net "M_B_CPU0_SA_DQ<16>")
		)
		(pad "30" smd rect
			(at -2.050034 -38.675056 270)
			(size 0.519938 1.4986)
			(layers "F.Cu" "F.Mask" "F.Paste")
			(net "GND")
		)
		(pad "31" smd rect
			(at -2.050034 -37.824918 270)
			(size 0.519938 1.4986)
			(layers "F.Cu" "F.Mask" "F.Paste")
			(net "M_B_CPU0_SA_DQ<17>")
		)
		(pad "32" smd rect
			(at -2.050034 -36.975034 270)
			(size 0.519938 1.4986)
			(layers "F.Cu" "F.Mask" "F.Paste")
			(net "GND")
		)
		(pad "33" smd rect
			(at -2.050034 -36.124896 270)
			(size 0.519938 1.4986)
			(layers "F.Cu" "F.Mask" "F.Paste")
			(net "M_B_CPU0_SA_DQS_DP<2>")
		)
		(pad "34" smd rect
			(at -2.050034 -35.275012 270)
			(size 0.519938 1.4986)
			(layers "F.Cu" "F.Mask" "F.Paste")
			(net "M_B_CPU0_SA_DQS_DN<2>")
		)
		(pad "35" smd rect
			(at -2.050034 -34.425128 270)
			(size 0.519938 1.4986)
			(layers "F.Cu" "F.Mask" "F.Paste")
			(net "GND")
		)
		(pad "36" smd rect
			(at -2.050034 -33.57499 270)
			(size 0.519938 1.4986)
			(layers "F.Cu" "F.Mask" "F.Paste")
			(net "M_B_CPU0_SA_DQ<20>")
		)
		(pad "37" smd rect
			(at -2.050034 -32.725106 270)
			(size 0.519938 1.4986)
			(layers "F.Cu" "F.Mask" "F.Paste")
			(net "GND")
		)
		(pad "38" smd rect
			(at -2.050034 -31.874968 270)
			(size 0.519938 1.4986)
			(layers "F.Cu" "F.Mask" "F.Paste")
			(net "M_B_CPU0_SA_DQ<21>")
		)
		(pad "39" smd rect
			(at -2.050034 -31.025084 270)
			(size 0.519938 1.4986)
			(layers "F.Cu" "F.Mask" "F.Paste")
			(net "GND")
		)
		(pad "40" smd rect
			(at -2.050034 -30.174946 270)
			(size 0.519938 1.4986)
			(layers "F.Cu" "F.Mask" "F.Paste")
			(net "M_B_CPU0_SA_DQ<24>")
		)
		(pad "41" smd rect
			(at -2.050034 -29.325062 270)
			(size 0.519938 1.4986)
			(layers "F.Cu" "F.Mask" "F.Paste")
			(net "GND")
		)
		(pad "42" smd rect
			(at -2.050034 -28.474924 270)
			(size 0.519938 1.4986)
			(layers "F.Cu" "F.Mask" "F.Paste")
			(net "M_B_CPU0_SA_DQ<25>")
		)
		(pad "43" smd rect
			(at -2.050034 -27.62504 270)
			(size 0.519938 1.4986)
			(layers "F.Cu" "F.Mask" "F.Paste")
			(net "GND")
		)
		(pad "44" smd rect
			(at -2.050034 -26.774902 270)
			(size 0.519938 1.4986)
			(layers "F.Cu" "F.Mask" "F.Paste")
			(net "M_B_CPU0_SA_DQS_DP<3>")
		)
		(pad "45" smd rect
			(at -2.050034 -25.925018 270)
			(size 0.519938 1.4986)
			(layers "F.Cu" "F.Mask" "F.Paste")
			(net "M_B_CPU0_SA_DQS_DN<3>")
		)
	)
)
